(kicad_pcb
	(version 20260206)
	(generator "pcbnew")
	(generator_version "10.0")
	(general
		(thickness 1.6)
		(legacy_teardrops no)
	)
	(paper "A4")
	(title_block
		(title "03242023_DA0F0TMBIJ0_F0T_Motherboard_J_brd_V01_OCP.brd")
		(comment 1 "Grand Teton / footprints 4021-4025 of 6105")
	)
	(layers
		(0 "F.Cu" signal "TOP")
		(4 "In1.Cu" signal "GND")
		(6 "In2.Cu" signal "IN1")
		(8 "In3.Cu" signal "GND1")
		(10 "In4.Cu" signal "IN2")
		(12 "In5.Cu" signal "GND2")
		(14 "In6.Cu" signal "IN3")
		(16 "In7.Cu" signal "GND3")
		(18 "In8.Cu" signal "VCC")
		(20 "In9.Cu" signal "VCC1")
		(22 "In10.Cu" signal "GND4")
		(24 "In11.Cu" signal "IN4")
		(26 "In12.Cu" signal "GND5")
		(28 "In13.Cu" signal "IN5")
		(30 "In14.Cu" signal "GND6")
		(32 "In15.Cu" signal "IN6")
		(34 "In16.Cu" signal "GND7")
		(2 "B.Cu" signal "BOTTOM")
		(9 "F.Adhes" user "F.Adhesive")
		(11 "B.Adhes" user "B.Adhesive")
		(13 "F.Paste" user "Package Geometry/Pastemask Top")
		(15 "B.Paste" user "Package Geometry/Pastemask Bottom")
		(5 "F.SilkS" user "Ref Des/Silkscreen Top")
		(7 "B.SilkS" user "Ref Des/Silkscreen Bottom")
		(1 "F.Mask" user "Board Geometry/Soldermask Top")
		(3 "B.Mask" user "Board Geometry/Soldermask Bottom")
		(17 "Dwgs.User" user "User.Drawings")
		(19 "Cmts.User" user "User.Comments")
		(21 "Eco1.User" user "User.Eco1")
		(23 "Eco2.User" user "User.Eco2")
		(25 "Edge.Cuts" user "Board Geometry/Outline")
		(27 "Margin" user)
		(31 "F.CrtYd" user "Package Geometry/Place Bound Top")
		(29 "B.CrtYd" user "Package Geometry/Place Bound Bottom")
		(35 "F.Fab" user "Ref Des/Assembly Top")
		(33 "B.Fab" user "Ref Des/Assembly Bottom")
	)
	(footprint ""
		(layer "F.Cu")
		(at 118.542816 -252.956568 -90)
		(property "Reference" "C243"
			(at 0 0 270)
			(layer "F.SilkS")
			(hide yes)
			(effects
				(font
					(size 1.27 1.27)
				)
			)
		)
		(property "Value" ""
			(at 0 0 270)
			(layer "F.Fab")
			(effects
				(font
					(size 1.27 1.27)
				)
			)
		)
		(duplicate_pad_numbers_are_jumpers no)
		(fp_line
			(start -0.7874 0.4064)
			(end -0.7874 -0.4064)
			(stroke
				(width 0.1524)
				(type default)
			)
			(layer "F.SilkS")
		)
		(fp_line
			(start 0.7874 0.4064)
			(end -0.7874 0.4064)
			(stroke
				(width 0.1524)
				(type default)
			)
			(layer "F.SilkS")
		)
		(fp_line
			(start -0.7874 -0.4064)
			(end 0.7874 -0.4064)
			(stroke
				(width 0.1524)
				(type default)
			)
			(layer "F.SilkS")
		)
		(fp_line
			(start 0.7874 -0.4064)
			(end 0.7874 0.4064)
			(stroke
				(width 0.1524)
				(type default)
			)
			(layer "F.SilkS")
		)
		(fp_line
			(start -0.67945 0.3048)
			(end -0.67945 -0.305054)
			(stroke
				(width 0.1)
				(type default)
			)
			(layer "F.Fab")
		)
		(fp_line
			(start -0.12065 0.3048)
			(end -0.67945 0.3048)
			(stroke
				(width 0.1)
				(type default)
			)
			(layer "F.Fab")
		)
		(fp_line
			(start 0.120396 0.3048)
			(end 0.120396 0.2794)
			(stroke
				(width 0.1)
				(type default)
			)
			(layer "F.Fab")
		)
		(fp_line
			(start 0.67945 0.3048)
			(end 0.120396 0.3048)
			(stroke
				(width 0.1)
				(type default)
			)
			(layer "F.Fab")
		)
		(fp_line
			(start -0.12065 0.2794)
			(end -0.12065 0.3048)
			(stroke
				(width 0.1)
				(type default)
			)
			(layer "F.Fab")
		)
		(fp_line
			(start 0.120396 0.2794)
			(end -0.12065 0.2794)
			(stroke
				(width 0.1)
				(type default)
			)
			(layer "F.Fab")
		)
		(fp_line
			(start -0.12065 -0.2794)
			(end 0.12065 -0.2794)
			(stroke
				(width 0.1)
				(type default)
			)
			(layer "F.Fab")
		)
		(fp_line
			(start 0.12065 -0.2794)
			(end 0.12065 -0.3048)
			(stroke
				(width 0.1)
				(type default)
			)
			(layer "F.Fab")
		)
		(fp_line
			(start 0.12065 -0.3048)
			(end 0.67945 -0.3048)
			(stroke
				(width 0.1)
				(type default)
			)
			(layer "F.Fab")
		)
		(fp_line
			(start 0.67945 -0.3048)
			(end 0.67945 0.3048)
			(stroke
				(width 0.1)
				(type default)
			)
			(layer "F.Fab")
		)
		(fp_line
			(start -0.67945 -0.305054)
			(end -0.12065 -0.305054)
			(stroke
				(width 0.1)
				(type default)
			)
			(layer "F.Fab")
		)
		(fp_line
			(start -0.12065 -0.305054)
			(end -0.12065 -0.2794)
			(stroke
				(width 0.1)
				(type default)
			)
			(layer "F.Fab")
		)
		(pad "1" smd circle
			(at -0.40005 0 270)
			(size 0 0)
			(layers "F.Cu" "F.Mask" "F.Paste")
			(net "PVCCIN_CPU1")
		)
		(pad "2" smd circle
			(at 0.40005 0 270)
			(size 0 0)
			(layers "F.Cu" "F.Mask" "F.Paste")
			(net "GND")
		)
	)
	(footprint ""
		(layer "F.Cu")
		(at 307.3146 -62.375542 90)
		(property "Reference" "C1612"
			(at 0 0 90)
			(layer "F.SilkS")
			(hide yes)
			(effects
				(font
					(size 1.27 1.27)
				)
			)
		)
		(property "Value" ""
			(at 0 0 90)
			(layer "F.Fab")
			(effects
				(font
					(size 1.27 1.27)
				)
			)
		)
		(duplicate_pad_numbers_are_jumpers no)
		(fp_line
			(start 0.7874 -0.4064)
			(end 0.7874 0.4064)
			(stroke
				(width 0.1524)
				(type default)
			)
			(layer "F.SilkS")
		)
		(fp_line
			(start -0.7874 -0.4064)
			(end 0.7874 -0.4064)
			(stroke
				(width 0.1524)
				(type default)
			)
			(layer "F.SilkS")
		)
		(fp_line
			(start 0.7874 0.4064)
			(end -0.7874 0.4064)
			(stroke
				(width 0.1524)
				(type default)
			)
			(layer "F.SilkS")
		)
		(fp_line
			(start -0.7874 0.4064)
			(end -0.7874 -0.4064)
			(stroke
				(width 0.1524)
				(type default)
			)
			(layer "F.SilkS")
		)
		(fp_line
			(start -0.12065 -0.305054)
			(end -0.12065 -0.2794)
			(stroke
				(width 0.1)
				(type default)
			)
			(layer "F.Fab")
		)
		(fp_line
			(start -0.67945 -0.305054)
			(end -0.12065 -0.305054)
			(stroke
				(width 0.1)
				(type default)
			)
			(layer "F.Fab")
		)
		(fp_line
			(start 0.67945 -0.3048)
			(end 0.67945 0.3048)
			(stroke
				(width 0.1)
				(type default)
			)
			(layer "F.Fab")
		)
		(fp_line
			(start 0.12065 -0.3048)
			(end 0.67945 -0.3048)
			(stroke
				(width 0.1)
				(type default)
			)
			(layer "F.Fab")
		)
		(fp_line
			(start 0.12065 -0.2794)
			(end 0.12065 -0.3048)
			(stroke
				(width 0.1)
				(type default)
			)
			(layer "F.Fab")
		)
		(fp_line
			(start -0.12065 -0.2794)
			(end 0.12065 -0.2794)
			(stroke
				(width 0.1)
				(type default)
			)
			(layer "F.Fab")
		)
		(fp_line
			(start 0.120396 0.2794)
			(end -0.12065 0.2794)
			(stroke
				(width 0.1)
				(type default)
			)
			(layer "F.Fab")
		)
		(fp_line
			(start -0.12065 0.2794)
			(end -0.12065 0.3048)
			(stroke
				(width 0.1)
				(type default)
			)
			(layer "F.Fab")
		)
		(fp_line
			(start 0.67945 0.3048)
			(end 0.120396 0.3048)
			(stroke
				(width 0.1)
				(type default)
			)
			(layer "F.Fab")
		)
		(fp_line
			(start 0.120396 0.3048)
			(end 0.120396 0.2794)
			(stroke
				(width 0.1)
				(type default)
			)
			(layer "F.Fab")
		)
		(fp_line
			(start -0.12065 0.3048)
			(end -0.67945 0.3048)
			(stroke
				(width 0.1)
				(type default)
			)
			(layer "F.Fab")
		)
		(fp_line
			(start -0.67945 0.3048)
			(end -0.67945 -0.305054)
			(stroke
				(width 0.1)
				(type default)
			)
			(layer "F.Fab")
		)
		(pad "1" smd circle
			(at -0.40005 0 90)
			(size 0 0)
			(layers "F.Cu" "F.Mask" "F.Paste")
			(net "P3V3_AUX")
		)
		(pad "2" smd circle
			(at 0.40005 0 90)
			(size 0 0)
			(layers "F.Cu" "F.Mask" "F.Paste")
			(net "GND")
		)
	)
	(footprint ""
		(layer "F.Cu")
		(at 31.891732 -416.016948 180)
		(property "Reference" "R2842"
			(at 0 0 180)
			(layer "F.SilkS")
			(hide yes)
			(effects
				(font
					(size 1.27 1.27)
				)
			)
		)
		(property "Value" ""
			(at 0 0 180)
			(layer "F.Fab")
			(effects
				(font
					(size 1.27 1.27)
				)
			)
		)
		(duplicate_pad_numbers_are_jumpers no)
		(fp_line
			(start 0.7874 0.4064)
			(end -0.7874 0.4064)
			(stroke
				(width 0.1524)
				(type default)
			)
			(layer "F.SilkS")
		)
		(fp_line
			(start 0.7874 -0.4064)
			(end 0.7874 0.4064)
			(stroke
				(width 0.1524)
				(type default)
			)
			(layer "F.SilkS")
		)
		(fp_line
			(start -0.7874 0.4064)
			(end -0.7874 -0.4064)
			(stroke
				(width 0.1524)
				(type default)
			)
			(layer "F.SilkS")
		)
		(fp_line
			(start -0.7874 -0.4064)
			(end 0.7874 -0.4064)
			(stroke
				(width 0.1524)
				(type default)
			)
			(layer "F.SilkS")
		)
		(fp_line
			(start 0.67945 0.3048)
			(end 0.120396 0.3048)
			(stroke
				(width 0.1)
				(type default)
			)
			(layer "F.Fab")
		)
		(fp_line
			(start 0.67945 -0.3048)
			(end 0.67945 0.3048)
			(stroke
				(width 0.1)
				(type default)
			)
			(layer "F.Fab")
		)
		(fp_line
			(start 0.12065 -0.2794)
			(end 0.12065 -0.3048)
			(stroke
				(width 0.1)
				(type default)
			)
			(layer "F.Fab")
		)
		(fp_line
			(start 0.12065 -0.3048)
			(end 0.67945 -0.3048)
			(stroke
				(width 0.1)
				(type default)
			)
			(layer "F.Fab")
		)
		(fp_line
			(start 0.120396 0.3048)
			(end 0.120396 0.2794)
			(stroke
				(width 0.1)
				(type default)
			)
			(layer "F.Fab")
		)
		(fp_line
			(start 0.120396 0.2794)
			(end -0.12065 0.2794)
			(stroke
				(width 0.1)
				(type default)
			)
			(layer "F.Fab")
		)
		(fp_line
			(start -0.12065 0.3048)
			(end -0.67945 0.3048)
			(stroke
				(width 0.1)
				(type default)
			)
			(layer "F.Fab")
		)
		(fp_line
			(start -0.12065 0.2794)
			(end -0.12065 0.3048)
			(stroke
				(width 0.1)
				(type default)
			)
			(layer "F.Fab")
		)
		(fp_line
			(start -0.12065 -0.2794)
			(end 0.12065 -0.2794)
			(stroke
				(width 0.1)
				(type default)
			)
			(layer "F.Fab")
		)
		(fp_line
			(start -0.12065 -0.305054)
			(end -0.12065 -0.2794)
			(stroke
				(width 0.1)
				(type default)
			)
			(layer "F.Fab")
		)
		(fp_line
			(start -0.67945 0.3048)
			(end -0.67945 -0.305054)
			(stroke
				(width 0.1)
				(type default)
			)
			(layer "F.Fab")
		)
		(fp_line
			(start -0.67945 -0.305054)
			(end -0.12065 -0.305054)
			(stroke
				(width 0.1)
				(type default)
			)
			(layer "F.Fab")
		)
		(pad "1" smd circle
			(at -0.40005 0 180)
			(size 0 0)
			(layers "F.Cu" "F.Mask" "F.Paste")
			(net "P3V3_AUX")
		)
		(pad "2" smd circle
			(at 0.40005 0 180)
			(size 0 0)
			(layers "F.Cu" "F.Mask" "F.Paste")
			(net "FM_GPU_PWRGD_N")
		)
	)
	(footprint ""
		(layer "F.Cu")
		(at 416.009582 -179.457858 -90)
		(property "Reference" "PU44_P0_2"
			(at 4.08051 7.755382 0)
			(unlocked yes)
			(layer "F.SilkS")
			(effects
				(font
					(size 0.7874 0.5842)
					(thickness 0.1524)
				)
				(justify left)
			)
		)
		(property "Value" ""
			(at 0 0 270)
			(layer "F.Fab")
			(effects
				(font
					(size 1.27 1.27)
				)
			)
		)
		(duplicate_pad_numbers_are_jumpers no)
		(fp_line
			(start -2.500122 2.999994)
			(end -2.500122 2.339594)
			(stroke
				(width 0.1524)
				(type default)
			)
			(layer "F.SilkS")
		)
		(fp_line
			(start -2.2987 2.999994)
			(end -2.500122 2.999994)
			(stroke
				(width 0.1524)
				(type default)
			)
			(layer "F.SilkS")
		)
		(fp_line
			(start 2.500122 2.999994)
			(end 2.2987 2.999994)
			(stroke
				(width 0.1524)
				(type default)
			)
			(layer "F.SilkS")
		)
		(fp_line
			(start 2.500122 2.339594)
			(end 2.500122 2.999994)
			(stroke
				(width 0.1524)
				(type default)
			)
			(layer "F.SilkS")
		)
		(fp_line
			(start -2.500122 0.6604)
			(end -2.500122 0.229108)
			(stroke
				(width 0.1524)
				(type default)
			)
			(layer "F.SilkS")
		)
		(fp_line
			(start -2.500122 -2.529078)
			(end -2.500122 -2.999994)
			(stroke
				(width 0.1524)
				(type default)
			)
			(layer "F.SilkS")
		)
		(fp_line
			(start -2.500122 -2.999994)
			(end -2.24409 -2.999994)
			(stroke
				(width 0.1524)
				(type default)
			)
			(layer "F.SilkS")
		)
		(fp_line
			(start 2.31394 -2.999994)
			(end 2.500122 -2.999994)
			(stroke
				(width 0.1524)
				(type default)
			)
			(layer "F.SilkS")
		)
		(fp_line
			(start 2.500122 -2.999994)
			(end 2.500122 -2.44348)
			(stroke
				(width 0.1524)
				(type default)
			)
			(layer "F.SilkS")
		)
		(fp_poly
			(pts
				(xy -4.93395 -2.65811) (xy -4.218432 -2.300478) (xy -4.93395 -1.942846)
			)
			(stroke
				(width 0)
				(type default)
			)
			(fill yes)
			(layer "F.SilkS")
		)
		(fp_line
			(start -2.500122 2.999994)
			(end -2.500122 -2.999994)
			(stroke
				(width 0.1)
				(type default)
			)
			(layer "F.Fab")
		)
		(fp_line
			(start 2.500122 2.999994)
			(end -2.500122 2.999994)
			(stroke
				(width 0.1)
				(type default)
			)
			(layer "F.Fab")
		)
		(fp_line
			(start -2.500122 -2.999994)
			(end 2.500122 -2.999994)
			(stroke
				(width 0.1)
				(type default)
			)
			(layer "F.Fab")
		)
		(fp_line
			(start 2.500122 -2.999994)
			(end 2.500122 2.999994)
			(stroke
				(width 0.1)
				(type default)
			)
			(layer "F.Fab")
		)
		(fp_poly
			(pts
				(xy -4.218432 -2.783078) (xy -4.218432 -1.767078) (xy -3.202432 -2.275078)
			)
			(stroke
				(width 0)
				(type default)
			)
			(fill yes)
			(layer "F.Fab")
		)
		(pad "1" smd rect
			(at -2.400046 -2.275078)
			(size 0.2286 0.6096)
			(layers "F.Cu" "F.Mask" "F.Paste")
			(net "PVCCINFAON_CPU0_VOS2")
		)
		(pad "2" smd rect
			(at -2.400046 -1.82499)
			(size 0.2286 0.6096)
			(layers "F.Cu" "F.Mask" "F.Paste")
			(net "GND")
		)
		(pad "3" smd rect
			(at -2.400046 -1.374902)
			(size 0.2286 0.6096)
			(layers "F.Cu" "F.Mask" "F.Paste")
			(net "PVCCINFAON_CPU0_VDD2")
		)
		(pad "4" smd rect
			(at -2.400046 -0.925068)
			(size 0.2286 0.6096)
			(layers "F.Cu" "F.Mask" "F.Paste")
			(net "PVCCFA_EHV_CPU0_PVCC")
		)
		(pad "5" smd rect
			(at -2.400046 -0.47498)
			(size 0.2286 0.6096)
			(layers "F.Cu" "F.Mask" "F.Paste")
			(net "GND")
		)
		(pad "6" smd rect
			(at -2.400046 -0.024892)
			(size 0.2286 0.6096)
			(layers "F.Cu" "F.Mask" "F.Paste")
			(net "Net_1926")
		)
		(pad "7_9-20_24" smd circle
			(at 0 1.150112)
			(size 0 0)
			(layers "F.Cu" "F.Mask" "F.Paste")
			(net "GND")
		)
		(pad "10_19" smd rect
			(at 0 2.899918)
			(size 0.6096 4.318)
			(layers "F.Cu" "F.Mask" "F.Paste")
			(net "SW_PVCCINFAON_CPU0_SW2")
		)
		(pad "25_29" smd rect
			(at 1.549908 -1.279906 180)
			(size 2.0574 2.3114)
			(layers "F.Cu" "F.Mask" "F.Paste")
			(net "SW_P12V_PVCCINFAON_CPU0_FLT")
		)
		(pad "30" smd rect
			(at 2.05994 -2.899918 270)
			(size 0.2286 0.6096)
			(layers "F.Cu" "F.Mask" "F.Paste")
			(net "SW_P12V_PVCCINFAON_CPU0_FLT")
		)
		(pad "31" smd rect
			(at 1.610106 -2.899918 270)
			(size 0.2286 0.6096)
			(layers "F.Cu" "F.Mask" "F.Paste")
			(net "Net_1925")
		)
		(pad "32" smd rect
			(at 1.160018 -2.899918 270)
			(size 0.2286 0.6096)
			(layers "F.Cu" "F.Mask" "F.Paste")
			(net "SW_PVCCINFAON_CPU0_BOOTR2")
		)
		(pad "33" smd rect
			(at 0.70993 -2.899918 270)
			(size 0.2286 0.6096)
			(layers "F.Cu" "F.Mask" "F.Paste")
			(net "SW_PVCCINFAON_CPU0_BOOT2")
		)
		(pad "34" smd rect
			(at 0.260096 -2.899918 270)
			(size 0.2286 0.6096)
			(layers "F.Cu" "F.Mask" "F.Paste")
			(net "PVCCINFAON_CPU0_APWM2")
		)
		(pad "35" smd rect
			(at -0.189992 -2.899918 270)
			(size 0.2286 0.6096)
			(layers "F.Cu" "F.Mask" "F.Paste")
			(net "PVCCINFAON_CPU0_VDD2")
		)
		(pad "36" smd rect
			(at -0.64008 -2.899918 270)
			(size 0.2286 0.6096)
			(layers "F.Cu" "F.Mask" "F.Paste")
			(net "PVCCINFAON_CPU0_ATSEN")
		)
		(pad "37" smd rect
			(at -1.089914 -2.899918 270)
			(size 0.2286 0.6096)
			(layers "F.Cu" "F.Mask" "F.Paste")
			(net "PVCCINFAON_CPU0_LSET2")
		)
		(pad "38" smd rect
			(at -1.540002 -2.899918 270)
			(size 0.2286 0.6096)
			(layers "F.Cu" "F.Mask" "F.Paste")
			(net "PVCCINFAON_CPU0_ACSP2")
		)
		(pad "39" smd rect
			(at -1.99009 -2.899918 270)
			(size 0.2286 0.6096)
			(layers "F.Cu" "F.Mask" "F.Paste")
			(net "PVCCINFAON_CPU0_VREF")
		)
		(pad "40" smd rect
			(at -0.87503 -1.27508 270)
			(size 1.7526 1.9558)
			(layers "F.Cu" "F.Mask" "F.Paste")
			(net "GND")
		)
		(pad "41" smd rect
			(at -1.525016 0.249936 180)
			(size 0.3048 0.4572)
			(layers "F.Cu" "F.Mask" "F.Paste")
			(net "Net_1927")
		)
		(zone
			(layer "F.Cu")
			(hatch none 0.5)
			(connect_pads
				(clearance 0)
			)
			(min_thickness 0.25)
			(keepout
				(tracks not_allowed)
				(vias allowed)
				(pads allowed)
				(copperpour not_allowed)
				(footprints allowed)
			)
			(placement
				(enabled no)
				(sheetname "")
			)
			(fill
				(thermal_gap 0.5)
				(thermal_bridge_width 0.5)
				(island_removal_mode 0)
			)
			(polygon
				(pts
					(xy 413.009588 -181.95798) (xy 413.540956 -181.95798) (xy 413.758888 -181.740048) (xy 413.758888 -177.168048)
					(xy 413.548576 -176.957736) (xy 413.009588 -176.957736) (xy 413.009588 -177.248058) (xy 413.465264 -177.248058)
					(xy 413.465264 -181.667658) (xy 413.009588 -181.667658)
				)
			)
		)
	)
	(footprint ""
		(layer "F.Cu")
		(at 344.691208 -402.371052 -90)
		(property "Reference" "C1553"
			(at 0 0 270)
			(layer "F.SilkS")
			(hide yes)
			(effects
				(font
					(size 1.27 1.27)
				)
			)
		)
		(property "Value" ""
			(at 0 0 270)
			(layer "F.Fab")
			(effects
				(font
					(size 1.27 1.27)
				)
			)
		)
		(duplicate_pad_numbers_are_jumpers no)
		(fp_line
			(start -0.299974 0.150114)
			(end -0.299974 -0.150114)
			(stroke
				(width 0.1)
				(type default)
			)
			(layer "F.Fab")
		)
		(fp_line
			(start 0.299974 0.150114)
			(end -0.299974 0.150114)
			(stroke
				(width 0.1)
				(type default)
			)
			(layer "F.Fab")
		)
		(fp_line
			(start -0.299974 -0.150114)
			(end 0.299974 -0.150114)
			(stroke
				(width 0.1)
				(type default)
			)
			(layer "F.Fab")
		)
		(fp_line
			(start 0.299974 -0.150114)
			(end 0.299974 0.150114)
			(stroke
				(width 0.1)
				(type default)
			)
			(layer "F.Fab")
		)
		(pad "1" smd rect
			(at -0.2667 0 270)
			(size 0.3048 0.381)
			(layers "F.Cu" "F.Mask" "F.Paste")
			(net "P5E_CPU0_PE4_TX_C_DP<13>")
		)
		(pad "2" smd rect
			(at 0.2667 0 270)
			(size 0.3048 0.381)
			(layers "F.Cu" "F.Mask" "F.Paste")
			(net "P5E_CPU0_PE4_TX_DP<13>")
		)
	)
)
